(kicad_pcb
	(version 20260206)
	(generator "pcbnew")
	(generator_version "10.0")
	(general
		(thickness 1.6)
		(legacy_teardrops no)
	)
	(paper "A4")
	(title_block
		(title "fcb — Lightning_FCB_BRD.brd")
		(comment 1 "Lightning (Wiwynn / Facebook NVMe JBOF) / footprints 257-262 of 495")
	)
	(layers
		(0 "F.Cu" signal "TOP")
		(4 "In1.Cu" signal "L2GND")
		(6 "In2.Cu" signal "L3VCC")
		(2 "B.Cu" signal "BOTTOM")
		(9 "F.Adhes" user "F.Adhesive")
		(11 "B.Adhes" user "B.Adhesive")
		(13 "F.Paste" user "Package Geometry/Pastemask Top")
		(15 "B.Paste" user "Package Geometry/Pastemask Bottom")
		(5 "F.SilkS" user "Ref Des/Silkscreen Top")
		(7 "B.SilkS" user "Ref Des/Silkscreen Bottom")
		(1 "F.Mask" user "Board Geometry/Soldermask Top")
		(3 "B.Mask" user "Board Geometry/Soldermask Bottom")
		(17 "Dwgs.User" user "User.Drawings")
		(19 "Cmts.User" user "User.Comments")
		(21 "Eco1.User" user "User.Eco1")
		(23 "Eco2.User" user "User.Eco2")
		(25 "Edge.Cuts" user "Board Geometry/Outline")
		(27 "Margin" user)
		(31 "F.CrtYd" user "Package Geometry/Place Bound Top")
		(29 "B.CrtYd" user "Package Geometry/Place Bound Bottom")
		(35 "F.Fab" user "Ref Des/Assembly Top")
		(33 "B.Fab" user "Ref Des/Assembly Bottom")
	)
	(footprint ""
		(layer "F.Cu")
		(at 14.4526 -60.5282)
		(property "Reference" "R362"
			(at 0 0 0)
			(layer "F.SilkS")
			(hide yes)
			(effects
				(font
					(size 1.27 1.27)
				)
			)
		)
		(property "Value" "100R2J-2-GP"
			(at 0.064008 -3.993896 0)
			(unlocked yes)
			(layer "F.Fab")
			(hide yes)
			(effects
				(font
					(size 1.016 1.016)
					(thickness 0.1524)
				)
			)
		)
		(property "Device Type" "R402H14"
			(at 0.064008 -5.517896 0)
			(unlocked yes)
			(layer "F.Fab")
			(hide yes)
			(effects
				(font
					(size 1.016 1.016)
					(thickness 0.1524)
				)
			)
		)
		(duplicate_pad_numbers_are_jumpers no)
		(fp_line
			(start -0.508 -0.9398)
			(end -0.508 0.9398)
			(stroke
				(width 0.1524)
				(type default)
			)
			(layer "F.SilkS")
		)
		(fp_line
			(start 0.508 -0.9398)
			(end -0.508 -0.9398)
			(stroke
				(width 0.1524)
				(type default)
			)
			(layer "F.SilkS")
		)
		(fp_rect
			(start -0.508 0.9398)
			(end 0.508 -0.9398)
			(stroke
				(width 0)
				(type default)
			)
			(fill no)
			(layer "F.CrtYd")
		)
		(fp_rect
			(start -0.508 0.9398)
			(end 0.508 -0.9398)
			(stroke
				(width 0)
				(type default)
			)
			(fill no)
			(layer "F.Fab")
		)
		(pad "1" smd custom
			(at 0 -0.4445)
			(size 0.1397 0.1397)
			(layers "F.Cu" "F.Mask" "F.Paste")
			(net "UPPER_TRAY_ID")
			(options
				(clearance outline)
				(anchor circle)
			)
			(primitives
				(gr_poly
					(pts
						(arc
							(start -0.1778 -0.2794)
							(mid -0.249642 -0.249642)
							(end -0.2794 -0.1778)
						)
						(arc
							(start -0.2794 0.1778)
							(mid -0.249642 0.249642)
							(end -0.1778 0.2794)
						)
						(arc
							(start 0.1778 0.2794)
							(mid 0.249642 0.249642)
							(end 0.2794 0.1778)
						)
						(arc
							(start 0.2794 -0.1778)
							(mid 0.249642 -0.249642)
							(end 0.1778 -0.2794)
						)
					)
					(width 0)
					(fill yes)
				)
			)
		)
		(pad "2" smd custom
			(at 0 0.4445)
			(size 0.1397 0.1397)
			(layers "F.Cu" "F.Mask" "F.Paste")
			(net "GND")
			(options
				(clearance outline)
				(anchor circle)
			)
			(primitives
				(gr_poly
					(pts
						(arc
							(start -0.1778 -0.2794)
							(mid -0.249642 -0.249642)
							(end -0.2794 -0.1778)
						)
						(arc
							(start -0.2794 0.1778)
							(mid -0.249642 0.249642)
							(end -0.1778 0.2794)
						)
						(arc
							(start 0.1778 0.2794)
							(mid 0.249642 0.249642)
							(end 0.2794 0.1778)
						)
						(arc
							(start 0.2794 -0.1778)
							(mid 0.249642 -0.249642)
							(end 0.1778 -0.2794)
						)
					)
					(width 0)
					(fill yes)
				)
			)
		)
	)
	(footprint ""
		(layer "F.Cu")
		(at 18.8214 -145.6436 180)
		(property "Reference" "PC91"
			(at 0 0 180)
			(layer "F.SilkS")
			(hide yes)
			(effects
				(font
					(size 1.27 1.27)
				)
			)
		)
		(property "Value" "SCD01U50V3KX-4GP"
			(at 0 -2.8194 180)
			(unlocked yes)
			(layer "F.Fab")
			(hide yes)
			(effects
				(font
					(size 1.016 1.016)
					(thickness 0.1524)
				)
			)
		)
		(property "Device Type" "C603H36"
			(at 0 -4.3434 180)
			(unlocked yes)
			(layer "F.Fab")
			(hide yes)
			(effects
				(font
					(size 1.016 1.016)
					(thickness 0.1524)
				)
			)
		)
		(duplicate_pad_numbers_are_jumpers no)
		(fp_line
			(start 0.508 0)
			(end -0.508 0)
			(stroke
				(width 0.2032)
				(type default)
			)
			(layer "F.SilkS")
		)
		(fp_rect
			(start -0.5842 1.3335)
			(end 0.5842 -1.3335)
			(stroke
				(width 0)
				(type default)
			)
			(fill no)
			(layer "F.CrtYd")
		)
		(fp_rect
			(start -0.5842 1.3335)
			(end 0.5842 -1.3335)
			(stroke
				(width 0)
				(type default)
			)
			(fill no)
			(layer "F.Fab")
		)
		(pad "1" smd custom
			(at 0 -0.762 180)
			(size 0.2159 0.2159)
			(layers "F.Cu" "F.Mask" "F.Paste")
			(net "P12VU_2490_TIMER")
			(options
				(clearance outline)
				(anchor circle)
			)
			(primitives
				(gr_poly
					(pts
						(arc
							(start -0.3302 -0.4318)
							(mid -0.402042 -0.402042)
							(end -0.4318 -0.3302)
						)
						(arc
							(start -0.4318 0.3302)
							(mid -0.402042 0.402042)
							(end -0.3302 0.4318)
						)
						(arc
							(start 0.3302 0.4318)
							(mid 0.402042 0.402042)
							(end 0.4318 0.3302)
						)
						(arc
							(start 0.4318 -0.3302)
							(mid 0.402042 -0.402042)
							(end 0.3302 -0.4318)
						)
					)
					(width 0)
					(fill yes)
				)
			)
		)
		(pad "2" smd custom
			(at 0 0.762 180)
			(size 0.2159 0.2159)
			(layers "F.Cu" "F.Mask" "F.Paste")
			(net "GND")
			(options
				(clearance outline)
				(anchor circle)
			)
			(primitives
				(gr_poly
					(pts
						(arc
							(start -0.3302 -0.4318)
							(mid -0.402042 -0.402042)
							(end -0.4318 -0.3302)
						)
						(arc
							(start -0.4318 0.3302)
							(mid -0.402042 0.402042)
							(end -0.3302 0.4318)
						)
						(arc
							(start 0.3302 0.4318)
							(mid 0.402042 0.402042)
							(end 0.4318 0.3302)
						)
						(arc
							(start 0.4318 -0.3302)
							(mid 0.402042 -0.402042)
							(end 0.3302 -0.4318)
						)
					)
					(width 0)
					(fill yes)
				)
			)
		)
	)
	(footprint ""
		(layer "F.Cu")
		(at 8.001 -169.418 -90)
		(property "Reference" "TC14"
			(at 0 0 270)
			(layer "F.SilkS")
			(hide yes)
			(effects
				(font
					(size 1.27 1.27)
				)
			)
		)
		(property "Value" "ST15U25VDM-1-GP"
			(at 0 -9.6012 270)
			(unlocked yes)
			(layer "F.Fab")
			(hide yes)
			(effects
				(font
					(size 1.016 1.016)
					(thickness 0.1524)
				)
			)
		)
		(property "Device Type" "CT7343H79"
			(at 0 -11.1252 270)
			(unlocked yes)
			(layer "F.Fab")
			(hide yes)
			(effects
				(font
					(size 1.016 1.016)
					(thickness 0.1524)
				)
			)
		)
		(duplicate_pad_numbers_are_jumpers no)
		(fp_line
			(start -2.286 4.8768)
			(end -2.286 2.032)
			(stroke
				(width 0.1524)
				(type default)
			)
			(layer "F.SilkS")
		)
		(fp_line
			(start 2.286 4.8768)
			(end -2.286 4.8768)
			(stroke
				(width 0.1524)
				(type default)
			)
			(layer "F.SilkS")
		)
		(fp_line
			(start 2.286 2.032)
			(end 2.286 4.8768)
			(stroke
				(width 0.1524)
				(type default)
			)
			(layer "F.SilkS")
		)
		(fp_line
			(start 2.286 -2.032)
			(end 2.286 -4.8768)
			(stroke
				(width 0.1524)
				(type default)
			)
			(layer "F.SilkS")
		)
		(fp_line
			(start 2.1082 -4.699)
			(end -2.1082 -4.699)
			(stroke
				(width 0.508)
				(type default)
			)
			(layer "F.SilkS")
		)
		(fp_line
			(start -2.286 -4.8768)
			(end -2.286 -2.032)
			(stroke
				(width 0.1524)
				(type default)
			)
			(layer "F.SilkS")
		)
		(fp_line
			(start 2.286 -4.8768)
			(end -2.286 -4.8768)
			(stroke
				(width 0.1524)
				(type default)
			)
			(layer "F.SilkS")
		)
		(fp_rect
			(start -2.1463 3.6449)
			(end 2.1463 -3.6449)
			(stroke
				(width 0)
				(type default)
			)
			(fill no)
			(layer "F.CrtYd")
		)
		(fp_poly
			(pts
				(xy -2.54 4.953) (xy -2.54 4.2926) (xy -3.81 4.2926) (xy -3.81 -4.2926) (xy -2.54 -4.2926) (xy -2.54 -4.953)
				(xy 2.54 -4.953) (xy 2.54 -4.2926) (xy 3.81 -4.2926) (xy 3.81 -1.6256) (xy 2.1463 -1.6256) (xy 2.1463 -3.6449)
				(xy -2.1463 -3.6449) (xy -2.1463 3.6449) (xy 2.1463 3.6449) (xy 2.1463 -1.6129) (xy 3.81 -1.6129)
				(xy 3.81 4.2926) (xy 2.54 4.2926) (xy 2.54 4.953)
			)
			(stroke
				(width 0)
				(type default)
			)
			(fill no)
			(layer "F.CrtYd")
		)
		(fp_rect
			(start -2.54 4.953)
			(end 2.54 -4.953)
			(stroke
				(width 0)
				(type default)
			)
			(fill no)
			(layer "F.Fab")
		)
		(fp_rect
			(start -3.81 4.2926)
			(end -2.54 -4.2926)
			(stroke
				(width 0)
				(type default)
			)
			(fill no)
			(layer "F.Fab")
		)
		(fp_rect
			(start 2.54 4.2926)
			(end 3.81 -4.2926)
			(stroke
				(width 0)
				(type default)
			)
			(fill no)
			(layer "F.Fab")
		)
		(pad "1" smd rect
			(at 0 -3.1496 270)
			(size 2.413 2.286)
			(layers "F.Cu" "F.Mask" "F.Paste")
			(net "P12V")
		)
		(pad "2" smd rect
			(at 0 3.1496 270)
			(size 2.413 2.286)
			(layers "F.Cu" "F.Mask" "F.Paste")
			(net "GND")
		)
		(zone
			(layer "F.Cu")
			(hatch none 0.5)
			(connect_pads
				(clearance 0)
			)
			(min_thickness 0.25)
			(keepout
				(tracks allowed)
				(vias not_allowed)
				(pads allowed)
				(copperpour not_allowed)
				(footprints allowed)
			)
			(placement
				(enabled no)
				(sheetname "")
			)
			(fill
				(thermal_gap 0.5)
				(thermal_bridge_width 0.5)
				(island_removal_mode 0)
			)
			(polygon
				(pts
					(xy 3.4036 -170.9293) (xy 3.4036 -167.9067) (xy 6.2992 -167.9067) (xy 6.6294 -167.9067) (xy 6.6294 -170.9293)
					(xy 6.2992 -170.9293)
				)
			)
		)
		(zone
			(layer "F.Cu")
			(hatch none 0.5)
			(connect_pads
				(clearance 0)
			)
			(min_thickness 0.25)
			(keepout
				(tracks allowed)
				(vias not_allowed)
				(pads allowed)
				(copperpour not_allowed)
				(footprints allowed)
			)
			(placement
				(enabled no)
				(sheetname "")
			)
			(fill
				(thermal_gap 0.5)
				(thermal_bridge_width 0.5)
				(island_removal_mode 0)
			)
			(polygon
				(pts
					(xy 9.6901 -167.9067) (xy 12.5984 -167.9067) (xy 12.5984 -170.9293) (xy 9.7028 -170.9293) (xy 9.3726 -170.9293)
					(xy 9.3726 -167.9067)
				)
			)
		)
	)
	(footprint ""
		(layer "F.Cu")
		(at 32.399224 -174.76851 90)
		(property "Reference" "R18"
			(at 0 0 90)
			(layer "F.SilkS")
			(hide yes)
			(effects
				(font
					(size 1.27 1.27)
				)
			)
		)
		(property "Value" "100KR2F-L1-GP"
			(at 0.064008 -3.993896 90)
			(unlocked yes)
			(layer "F.Fab")
			(hide yes)
			(effects
				(font
					(size 1.016 1.016)
					(thickness 0.1524)
				)
			)
		)
		(property "Device Type" "R402H16"
			(at 0.064008 -5.517896 90)
			(unlocked yes)
			(layer "F.Fab")
			(hide yes)
			(effects
				(font
					(size 1.016 1.016)
					(thickness 0.1524)
				)
			)
		)
		(duplicate_pad_numbers_are_jumpers no)
		(fp_line
			(start 0.508 -0.9398)
			(end -0.508 -0.9398)
			(stroke
				(width 0.1524)
				(type default)
			)
			(layer "F.SilkS")
		)
		(fp_line
			(start -0.508 -0.9398)
			(end -0.508 0.9398)
			(stroke
				(width 0.1524)
				(type default)
			)
			(layer "F.SilkS")
		)
		(fp_rect
			(start -0.508 0.9398)
			(end 0.508 -0.9398)
			(stroke
				(width 0)
				(type default)
			)
			(fill no)
			(layer "F.CrtYd")
		)
		(fp_rect
			(start -0.508 0.9398)
			(end 0.508 -0.9398)
			(stroke
				(width 0)
				(type default)
			)
			(fill no)
			(layer "F.Fab")
		)
		(pad "1" smd custom
			(at 0 -0.4445 90)
			(size 0.1397 0.1397)
			(layers "F.Cu" "F.Mask" "F.Paste")
			(net "PWM_EXP_1B")
			(options
				(clearance outline)
				(anchor circle)
			)
			(primitives
				(gr_poly
					(pts
						(arc
							(start -0.1778 -0.2794)
							(mid -0.249642 -0.249642)
							(end -0.2794 -0.1778)
						)
						(arc
							(start -0.2794 0.1778)
							(mid -0.249642 0.249642)
							(end -0.1778 0.2794)
						)
						(arc
							(start 0.1778 0.2794)
							(mid 0.249642 0.249642)
							(end 0.2794 0.1778)
						)
						(arc
							(start 0.2794 -0.1778)
							(mid 0.249642 -0.249642)
							(end 0.1778 -0.2794)
						)
					)
					(width 0)
					(fill yes)
				)
			)
		)
		(pad "2" smd custom
			(at 0 0.4445 90)
			(size 0.1397 0.1397)
			(layers "F.Cu" "F.Mask" "F.Paste")
			(net "GND")
			(options
				(clearance outline)
				(anchor circle)
			)
			(primitives
				(gr_poly
					(pts
						(arc
							(start -0.1778 -0.2794)
							(mid -0.249642 -0.249642)
							(end -0.2794 -0.1778)
						)
						(arc
							(start -0.2794 0.1778)
							(mid -0.249642 0.249642)
							(end -0.1778 0.2794)
						)
						(arc
							(start 0.1778 0.2794)
							(mid 0.249642 0.249642)
							(end 0.2794 0.1778)
						)
						(arc
							(start 0.2794 -0.1778)
							(mid 0.249642 -0.249642)
							(end 0.1778 -0.2794)
						)
					)
					(width 0)
					(fill yes)
				)
			)
		)
	)
	(footprint ""
		(layer "F.Cu")
		(at 13.97 -174.752 90)
		(property "Reference" "U11"
			(at 0 0 90)
			(layer "F.SilkS")
			(hide yes)
			(effects
				(font
					(size 1.27 1.27)
				)
			)
		)
		(property "Value" "74LVC1G32GW-1GP"
			(at -2.3368 -8.6868 90)
			(unlocked yes)
			(layer "F.Fab")
			(hide yes)
			(effects
				(font
					(size 1.016 1.016)
					(thickness 0.1524)
				)
			)
		)
		(property "Device Type" "SC70-5H44"
			(at -2.3114 -10.414 90)
			(unlocked yes)
			(layer "F.Fab")
			(hide yes)
			(effects
				(font
					(size 1.016 1.016)
					(thickness 0.1524)
				)
			)
		)
		(duplicate_pad_numbers_are_jumpers no)
		(fp_line
			(start 1.3843 -1.8034)
			(end 1.3843 -1.1176)
			(stroke
				(width 0.3302)
				(type default)
			)
			(layer "F.SilkS")
		)
		(fp_line
			(start 0.6604 -1.8034)
			(end 1.3843 -1.8034)
			(stroke
				(width 0.3302)
				(type default)
			)
			(layer "F.SilkS")
		)
		(fp_line
			(start 1.27 -1.7018)
			(end 1.27 1.7018)
			(stroke
				(width 0.1524)
				(type default)
			)
			(layer "F.SilkS")
		)
		(fp_line
			(start -1.27 -1.7018)
			(end 1.27 -1.7018)
			(stroke
				(width 0.1524)
				(type default)
			)
			(layer "F.SilkS")
		)
		(fp_line
			(start 1.27 1.7018)
			(end -1.27 1.7018)
			(stroke
				(width 0.1524)
				(type default)
			)
			(layer "F.SilkS")
		)
		(fp_line
			(start -1.27 1.7018)
			(end -1.27 -1.7018)
			(stroke
				(width 0.1524)
				(type default)
			)
			(layer "F.SilkS")
		)
		(fp_rect
			(start -1.524 1.9558)
			(end 1.524 -1.9558)
			(stroke
				(width 0)
				(type default)
			)
			(fill no)
			(layer "F.CrtYd")
		)
		(fp_poly
			(pts
				(xy -1.524 -1.9558) (xy 1.524 -1.9558) (xy 1.524 1.9558) (xy -1.524 1.9558)
			)
			(stroke
				(width 0)
				(type default)
			)
			(fill no)
			(layer "F.Fab")
		)
		(pad "1" smd rect
			(at 0.65024 -0.8255 90)
			(size 0.4064 1.2192)
			(layers "F.Cu" "F.Mask" "F.Paste")
			(net "SEB_PEER_2A_HB")
		)
		(pad "2" smd rect
			(at 0 -0.8255 90)
			(size 0.4064 1.2192)
			(layers "F.Cu" "F.Mask" "F.Paste")
			(net "SEB_PEER_2B_HB")
		)
		(pad "3" smd rect
			(at -0.65024 -0.8255 90)
			(size 0.4064 1.2192)
			(layers "F.Cu" "F.Mask" "F.Paste")
			(net "GND")
		)
		(pad "4" smd rect
			(at -0.65024 0.8255 90)
			(size 0.4064 1.2192)
			(layers "F.Cu" "F.Mask" "F.Paste")
			(net "SEB_PEER_2A_2B_HB_OUT")
		)
		(pad "5" smd rect
			(at 0.65024 0.8255 90)
			(size 0.4064 1.2192)
			(layers "F.Cu" "F.Mask" "F.Paste")
			(net "P3V3")
		)
	)
	(footprint ""
		(layer "F.Cu")
		(at 14.5796 -53.2384)
		(property "Reference" "R360"
			(at 0 0 0)
			(layer "F.SilkS")
			(hide yes)
			(effects
				(font
					(size 1.27 1.27)
				)
			)
		)
		(property "Value" "100R2J-2-GP"
			(at 0.064008 -3.993896 0)
			(unlocked yes)
			(layer "F.Fab")
			(hide yes)
			(effects
				(font
					(size 1.016 1.016)
					(thickness 0.1524)
				)
			)
		)
		(property "Device Type" "R402H14"
			(at 0.064008 -5.517896 0)
			(unlocked yes)
			(layer "F.Fab")
			(hide yes)
			(effects
				(font
					(size 1.016 1.016)
					(thickness 0.1524)
				)
			)
		)
		(duplicate_pad_numbers_are_jumpers no)
		(fp_line
			(start -0.508 -0.9398)
			(end -0.508 0.9398)
			(stroke
				(width 0.1524)
				(type default)
			)
			(layer "F.SilkS")
		)
		(fp_line
			(start 0.508 -0.9398)
			(end -0.508 -0.9398)
			(stroke
				(width 0.1524)
				(type default)
			)
			(layer "F.SilkS")
		)
		(fp_rect
			(start -0.508 0.9398)
			(end 0.508 -0.9398)
			(stroke
				(width 0)
				(type default)
			)
			(fill no)
			(layer "F.CrtYd")
		)
		(fp_rect
			(start -0.508 0.9398)
			(end 0.508 -0.9398)
			(stroke
				(width 0)
				(type default)
			)
			(fill no)
			(layer "F.Fab")
		)
		(pad "1" smd custom
			(at 0 -0.4445)
			(size 0.1397 0.1397)
			(layers "F.Cu" "F.Mask" "F.Paste")
			(net "FCB_HW_REVISION")
			(options
				(clearance outline)
				(anchor circle)
			)
			(primitives
				(gr_poly
					(pts
						(arc
							(start -0.1778 -0.2794)
							(mid -0.249642 -0.249642)
							(end -0.2794 -0.1778)
						)
						(arc
							(start -0.2794 0.1778)
							(mid -0.249642 0.249642)
							(end -0.1778 0.2794)
						)
						(arc
							(start 0.1778 0.2794)
							(mid 0.249642 0.249642)
							(end 0.2794 0.1778)
						)
						(arc
							(start 0.2794 -0.1778)
							(mid 0.249642 -0.249642)
							(end 0.1778 -0.2794)
						)
					)
					(width 0)
					(fill yes)
				)
			)
		)
		(pad "2" smd custom
			(at 0 0.4445)
			(size 0.1397 0.1397)
			(layers "F.Cu" "F.Mask" "F.Paste")
			(net "GND")
			(options
				(clearance outline)
				(anchor circle)
			)
			(primitives
				(gr_poly
					(pts
						(arc
							(start -0.1778 -0.2794)
							(mid -0.249642 -0.249642)
							(end -0.2794 -0.1778)
						)
						(arc
							(start -0.2794 0.1778)
							(mid -0.249642 0.249642)
							(end -0.1778 0.2794)
						)
						(arc
							(start 0.1778 0.2794)
							(mid 0.249642 0.249642)
							(end 0.2794 0.1778)
						)
						(arc
							(start 0.2794 -0.1778)
							(mid 0.249642 -0.249642)
							(end 0.1778 -0.2794)
						)
					)
					(width 0)
					(fill yes)
				)
			)
		)
	)
)
